(kicad_pcb
	(version 20260206)
	(generator "pcbnew")
	(generator_version "10.0")
	(general
		(thickness 1.6)
		(legacy_teardrops no)
	)
	(paper "A4")
	(title_block
		(title "04192023_DAF0TMB3IC0_F0TG_MB_C_brd_V02_OCP.brd")
		(comment 1 "Grand Teton / footprints 6888-6894 of 8354")
	)
	(layers
		(0 "F.Cu" signal "TOP")
		(4 "In1.Cu" signal "GND")
		(6 "In2.Cu" signal "IN1")
		(8 "In3.Cu" signal "GND1")
		(10 "In4.Cu" signal "IN2")
		(12 "In5.Cu" signal "GND2")
		(14 "In6.Cu" signal "IN3")
		(16 "In7.Cu" signal "GND3")
		(18 "In8.Cu" signal "VCC")
		(20 "In9.Cu" signal "VCC1")
		(22 "In10.Cu" signal "GND4")
		(24 "In11.Cu" signal "IN4")
		(26 "In12.Cu" signal "GND5")
		(28 "In13.Cu" signal "IN5")
		(30 "In14.Cu" signal "GND6")
		(32 "In15.Cu" signal "IN6")
		(34 "In16.Cu" signal "GND7")
		(2 "B.Cu" signal "BOTTOM")
		(9 "F.Adhes" user "F.Adhesive")
		(11 "B.Adhes" user "B.Adhesive")
		(13 "F.Paste" user "Package Geometry/Pastemask Top")
		(15 "B.Paste" user "Package Geometry/Pastemask Bottom")
		(5 "F.SilkS" user "Ref Des/Silkscreen Top")
		(7 "B.SilkS" user "Ref Des/Silkscreen Bottom")
		(1 "F.Mask" user "Board Geometry/Soldermask Top")
		(3 "B.Mask" user "Board Geometry/Soldermask Bottom")
		(17 "Dwgs.User" user "User.Drawings")
		(19 "Cmts.User" user "User.Comments")
		(21 "Eco1.User" user "User.Eco1")
		(23 "Eco2.User" user "User.Eco2")
		(25 "Edge.Cuts" user "Board Geometry/Outline")
		(27 "Margin" user)
		(31 "F.CrtYd" user "Package Geometry/Place Bound Top")
		(29 "B.CrtYd" user "Package Geometry/Place Bound Bottom")
		(35 "F.Fab" user "Ref Des/Assembly Top")
		(33 "B.Fab" user "Ref Des/Assembly Bottom")
	)
	(footprint ""
		(layer "B.Cu")
		(at 369.646454 -252.54331)
		(property "Reference" "C2134"
			(at 0 0 0)
			(layer "B.SilkS")
			(hide yes)
			(effects
				(font
					(size 1.27 1.27)
				)
				(justify mirror)
			)
		)
		(property "Value" ""
			(at 0 0 0)
			(layer "B.Fab")
			(effects
				(font
					(size 1.27 1.27)
				)
				(justify mirror)
			)
		)
		(duplicate_pad_numbers_are_jumpers no)
		(fp_line
			(start -0.7874 -0.4064)
			(end -0.7874 0.4064)
			(stroke
				(width 0.1524)
				(type default)
			)
			(layer "B.SilkS")
		)
		(fp_line
			(start -0.7874 0.4064)
			(end 0.7874 0.4064)
			(stroke
				(width 0.1524)
				(type default)
			)
			(layer "B.SilkS")
		)
		(fp_line
			(start 0.7874 -0.4064)
			(end -0.7874 -0.4064)
			(stroke
				(width 0.1524)
				(type default)
			)
			(layer "B.SilkS")
		)
		(fp_line
			(start 0.7874 0.4064)
			(end 0.7874 -0.4064)
			(stroke
				(width 0.1524)
				(type default)
			)
			(layer "B.SilkS")
		)
		(fp_line
			(start -0.67945 -0.3048)
			(end -0.67945 0.3048)
			(stroke
				(width 0.1)
				(type default)
			)
			(layer "B.Fab")
		)
		(fp_line
			(start -0.67945 0.3048)
			(end -0.120396 0.3048)
			(stroke
				(width 0.1)
				(type default)
			)
			(layer "B.Fab")
		)
		(fp_line
			(start -0.12065 -0.3048)
			(end -0.67945 -0.3048)
			(stroke
				(width 0.1)
				(type default)
			)
			(layer "B.Fab")
		)
		(fp_line
			(start -0.12065 -0.2794)
			(end -0.12065 -0.3048)
			(stroke
				(width 0.1)
				(type default)
			)
			(layer "B.Fab")
		)
		(fp_line
			(start -0.120396 0.2794)
			(end 0.12065 0.2794)
			(stroke
				(width 0.1)
				(type default)
			)
			(layer "B.Fab")
		)
		(fp_line
			(start -0.120396 0.3048)
			(end -0.120396 0.2794)
			(stroke
				(width 0.1)
				(type default)
			)
			(layer "B.Fab")
		)
		(fp_line
			(start 0.12065 -0.305054)
			(end 0.12065 -0.2794)
			(stroke
				(width 0.1)
				(type default)
			)
			(layer "B.Fab")
		)
		(fp_line
			(start 0.12065 -0.2794)
			(end -0.12065 -0.2794)
			(stroke
				(width 0.1)
				(type default)
			)
			(layer "B.Fab")
		)
		(fp_line
			(start 0.12065 0.2794)
			(end 0.12065 0.3048)
			(stroke
				(width 0.1)
				(type default)
			)
			(layer "B.Fab")
		)
		(fp_line
			(start 0.12065 0.3048)
			(end 0.67945 0.3048)
			(stroke
				(width 0.1)
				(type default)
			)
			(layer "B.Fab")
		)
		(fp_line
			(start 0.67945 -0.305054)
			(end 0.12065 -0.305054)
			(stroke
				(width 0.1)
				(type default)
			)
			(layer "B.Fab")
		)
		(fp_line
			(start 0.67945 0.3048)
			(end 0.67945 -0.305054)
			(stroke
				(width 0.1)
				(type default)
			)
			(layer "B.Fab")
		)
		(pad "1" smd circle
			(at 0.40005 0 180)
			(size 0 0)
			(layers "B.Cu" "B.Mask" "B.Paste")
			(net "PVDDCR_SOC_P0")
		)
		(pad "2" smd circle
			(at -0.40005 0 180)
			(size 0 0)
			(layers "B.Cu" "B.Mask" "B.Paste")
			(net "GND")
		)
	)
	(footprint ""
		(layer "B.Cu")
		(at 311.427876 -76.489814 -90)
		(property "Reference" "R3047"
			(at 0 0 90)
			(layer "B.SilkS")
			(hide yes)
			(effects
				(font
					(size 1.27 1.27)
				)
				(justify mirror)
			)
		)
		(property "Value" ""
			(at 0 0 90)
			(layer "B.Fab")
			(effects
				(font
					(size 1.27 1.27)
				)
				(justify mirror)
			)
		)
		(duplicate_pad_numbers_are_jumpers no)
		(fp_line
			(start -0.7874 0.4064)
			(end 0.7874 0.4064)
			(stroke
				(width 0.1524)
				(type default)
			)
			(layer "B.SilkS")
		)
		(fp_line
			(start 0.7874 0.4064)
			(end 0.7874 -0.4064)
			(stroke
				(width 0.1524)
				(type default)
			)
			(layer "B.SilkS")
		)
		(fp_line
			(start -0.7874 -0.4064)
			(end -0.7874 0.4064)
			(stroke
				(width 0.1524)
				(type default)
			)
			(layer "B.SilkS")
		)
		(fp_line
			(start 0.7874 -0.4064)
			(end -0.7874 -0.4064)
			(stroke
				(width 0.1524)
				(type default)
			)
			(layer "B.SilkS")
		)
		(fp_line
			(start -0.67945 0.3048)
			(end -0.120396 0.3048)
			(stroke
				(width 0.1)
				(type default)
			)
			(layer "B.Fab")
		)
		(fp_line
			(start -0.120396 0.3048)
			(end -0.120396 0.2794)
			(stroke
				(width 0.1)
				(type default)
			)
			(layer "B.Fab")
		)
		(fp_line
			(start 0.12065 0.3048)
			(end 0.67945 0.3048)
			(stroke
				(width 0.1)
				(type default)
			)
			(layer "B.Fab")
		)
		(fp_line
			(start 0.67945 0.3048)
			(end 0.67945 -0.305054)
			(stroke
				(width 0.1)
				(type default)
			)
			(layer "B.Fab")
		)
		(fp_line
			(start -0.120396 0.2794)
			(end 0.12065 0.2794)
			(stroke
				(width 0.1)
				(type default)
			)
			(layer "B.Fab")
		)
		(fp_line
			(start 0.12065 0.2794)
			(end 0.12065 0.3048)
			(stroke
				(width 0.1)
				(type default)
			)
			(layer "B.Fab")
		)
		(fp_line
			(start -0.12065 -0.2794)
			(end -0.12065 -0.3048)
			(stroke
				(width 0.1)
				(type default)
			)
			(layer "B.Fab")
		)
		(fp_line
			(start 0.12065 -0.2794)
			(end -0.12065 -0.2794)
			(stroke
				(width 0.1)
				(type default)
			)
			(layer "B.Fab")
		)
		(fp_line
			(start -0.67945 -0.3048)
			(end -0.67945 0.3048)
			(stroke
				(width 0.1)
				(type default)
			)
			(layer "B.Fab")
		)
		(fp_line
			(start -0.12065 -0.3048)
			(end -0.67945 -0.3048)
			(stroke
				(width 0.1)
				(type default)
			)
			(layer "B.Fab")
		)
		(fp_line
			(start 0.12065 -0.305054)
			(end 0.12065 -0.2794)
			(stroke
				(width 0.1)
				(type default)
			)
			(layer "B.Fab")
		)
		(fp_line
			(start 0.67945 -0.305054)
			(end 0.12065 -0.305054)
			(stroke
				(width 0.1)
				(type default)
			)
			(layer "B.Fab")
		)
		(pad "1" smd circle
			(at 0.40005 0 90)
			(size 0 0)
			(layers "B.Cu" "B.Mask" "B.Paste")
			(net "MB0_P12V_STBY_PWRGD")
		)
		(pad "2" smd circle
			(at -0.40005 0 90)
			(size 0 0)
			(layers "B.Cu" "B.Mask" "B.Paste")
			(net "PWRGD_PS_PWROK_PLD")
		)
	)
	(footprint ""
		(layer "B.Cu")
		(at 193.205608 -126.833376 -90)
		(property "Reference" "R395"
			(at 0 0 90)
			(layer "B.SilkS")
			(hide yes)
			(effects
				(font
					(size 1.27 1.27)
				)
				(justify mirror)
			)
		)
		(property "Value" ""
			(at 0 0 90)
			(layer "B.Fab")
			(effects
				(font
					(size 1.27 1.27)
				)
				(justify mirror)
			)
		)
		(duplicate_pad_numbers_are_jumpers no)
		(fp_line
			(start -0.7874 0.4064)
			(end 0.7874 0.4064)
			(stroke
				(width 0.1524)
				(type default)
			)
			(layer "B.SilkS")
		)
		(fp_line
			(start 0.7874 0.4064)
			(end 0.7874 -0.4064)
			(stroke
				(width 0.1524)
				(type default)
			)
			(layer "B.SilkS")
		)
		(fp_line
			(start -0.7874 -0.4064)
			(end -0.7874 0.4064)
			(stroke
				(width 0.1524)
				(type default)
			)
			(layer "B.SilkS")
		)
		(fp_line
			(start 0.7874 -0.4064)
			(end -0.7874 -0.4064)
			(stroke
				(width 0.1524)
				(type default)
			)
			(layer "B.SilkS")
		)
		(fp_line
			(start -0.67945 0.3048)
			(end -0.120396 0.3048)
			(stroke
				(width 0.1)
				(type default)
			)
			(layer "B.Fab")
		)
		(fp_line
			(start -0.120396 0.3048)
			(end -0.120396 0.2794)
			(stroke
				(width 0.1)
				(type default)
			)
			(layer "B.Fab")
		)
		(fp_line
			(start 0.12065 0.3048)
			(end 0.67945 0.3048)
			(stroke
				(width 0.1)
				(type default)
			)
			(layer "B.Fab")
		)
		(fp_line
			(start 0.67945 0.3048)
			(end 0.67945 -0.305054)
			(stroke
				(width 0.1)
				(type default)
			)
			(layer "B.Fab")
		)
		(fp_line
			(start -0.120396 0.2794)
			(end 0.12065 0.2794)
			(stroke
				(width 0.1)
				(type default)
			)
			(layer "B.Fab")
		)
		(fp_line
			(start 0.12065 0.2794)
			(end 0.12065 0.3048)
			(stroke
				(width 0.1)
				(type default)
			)
			(layer "B.Fab")
		)
		(fp_line
			(start -0.12065 -0.2794)
			(end -0.12065 -0.3048)
			(stroke
				(width 0.1)
				(type default)
			)
			(layer "B.Fab")
		)
		(fp_line
			(start 0.12065 -0.2794)
			(end -0.12065 -0.2794)
			(stroke
				(width 0.1)
				(type default)
			)
			(layer "B.Fab")
		)
		(fp_line
			(start -0.67945 -0.3048)
			(end -0.67945 0.3048)
			(stroke
				(width 0.1)
				(type default)
			)
			(layer "B.Fab")
		)
		(fp_line
			(start -0.12065 -0.3048)
			(end -0.67945 -0.3048)
			(stroke
				(width 0.1)
				(type default)
			)
			(layer "B.Fab")
		)
		(fp_line
			(start 0.12065 -0.305054)
			(end 0.12065 -0.2794)
			(stroke
				(width 0.1)
				(type default)
			)
			(layer "B.Fab")
		)
		(fp_line
			(start 0.67945 -0.305054)
			(end 0.12065 -0.305054)
			(stroke
				(width 0.1)
				(type default)
			)
			(layer "B.Fab")
		)
		(pad "1" smd circle
			(at 0.40005 0 90)
			(size 0 0)
			(layers "B.Cu" "B.Mask" "B.Paste")
			(net "FM_SPD_CPU0_SWITCH_CTRL_R_N")
		)
		(pad "2" smd circle
			(at -0.40005 0 90)
			(size 0 0)
			(layers "B.Cu" "B.Mask" "B.Paste")
			(net "FM_SPD_CPU0_SWITCH_CTRL_N")
		)
	)
	(footprint ""
		(layer "B.Cu")
		(at 195.359782 -194.885564 180)
		(property "Reference" "R777"
			(at 0 0 0)
			(layer "B.SilkS")
			(hide yes)
			(effects
				(font
					(size 1.27 1.27)
				)
				(justify mirror)
			)
		)
		(property "Value" ""
			(at 0 0 0)
			(layer "B.Fab")
			(effects
				(font
					(size 1.27 1.27)
				)
				(justify mirror)
			)
		)
		(duplicate_pad_numbers_are_jumpers no)
		(fp_line
			(start 0.7874 0.4064)
			(end 0.7874 -0.4064)
			(stroke
				(width 0.1524)
				(type default)
			)
			(layer "B.SilkS")
		)
		(fp_line
			(start 0.7874 -0.4064)
			(end -0.7874 -0.4064)
			(stroke
				(width 0.1524)
				(type default)
			)
			(layer "B.SilkS")
		)
		(fp_line
			(start -0.7874 0.4064)
			(end 0.7874 0.4064)
			(stroke
				(width 0.1524)
				(type default)
			)
			(layer "B.SilkS")
		)
		(fp_line
			(start -0.7874 -0.4064)
			(end -0.7874 0.4064)
			(stroke
				(width 0.1524)
				(type default)
			)
			(layer "B.SilkS")
		)
		(fp_line
			(start 0.67945 0.3048)
			(end 0.67945 -0.305054)
			(stroke
				(width 0.1)
				(type default)
			)
			(layer "B.Fab")
		)
		(fp_line
			(start 0.67945 -0.305054)
			(end 0.12065 -0.305054)
			(stroke
				(width 0.1)
				(type default)
			)
			(layer "B.Fab")
		)
		(fp_line
			(start 0.12065 0.3048)
			(end 0.67945 0.3048)
			(stroke
				(width 0.1)
				(type default)
			)
			(layer "B.Fab")
		)
		(fp_line
			(start 0.12065 0.2794)
			(end 0.12065 0.3048)
			(stroke
				(width 0.1)
				(type default)
			)
			(layer "B.Fab")
		)
		(fp_line
			(start 0.12065 -0.2794)
			(end -0.12065 -0.2794)
			(stroke
				(width 0.1)
				(type default)
			)
			(layer "B.Fab")
		)
		(fp_line
			(start 0.12065 -0.305054)
			(end 0.12065 -0.2794)
			(stroke
				(width 0.1)
				(type default)
			)
			(layer "B.Fab")
		)
		(fp_line
			(start -0.120396 0.3048)
			(end -0.120396 0.2794)
			(stroke
				(width 0.1)
				(type default)
			)
			(layer "B.Fab")
		)
		(fp_line
			(start -0.120396 0.2794)
			(end 0.12065 0.2794)
			(stroke
				(width 0.1)
				(type default)
			)
			(layer "B.Fab")
		)
		(fp_line
			(start -0.12065 -0.2794)
			(end -0.12065 -0.3048)
			(stroke
				(width 0.1)
				(type default)
			)
			(layer "B.Fab")
		)
		(fp_line
			(start -0.12065 -0.3048)
			(end -0.67945 -0.3048)
			(stroke
				(width 0.1)
				(type default)
			)
			(layer "B.Fab")
		)
		(fp_line
			(start -0.67945 0.3048)
			(end -0.120396 0.3048)
			(stroke
				(width 0.1)
				(type default)
			)
			(layer "B.Fab")
		)
		(fp_line
			(start -0.67945 -0.3048)
			(end -0.67945 0.3048)
			(stroke
				(width 0.1)
				(type default)
			)
			(layer "B.Fab")
		)
		(pad "1" smd circle
			(at 0.40005 0)
			(size 0 0)
			(layers "B.Cu" "B.Mask" "B.Paste")
			(net "PD_CHK_CPU1_DIMM_SAA")
		)
		(pad "2" smd circle
			(at -0.40005 0)
			(size 0 0)
			(layers "B.Cu" "B.Mask" "B.Paste")
			(net "GND")
		)
	)
	(footprint ""
		(layer "B.Cu")
		(at 359.721404 -254.44831 180)
		(property "Reference" "C2140"
			(at 0 0 0)
			(layer "B.SilkS")
			(hide yes)
			(effects
				(font
					(size 1.27 1.27)
				)
				(justify mirror)
			)
		)
		(property "Value" ""
			(at 0 0 0)
			(layer "B.Fab")
			(effects
				(font
					(size 1.27 1.27)
				)
				(justify mirror)
			)
		)
		(duplicate_pad_numbers_are_jumpers no)
		(fp_line
			(start 0.7874 0.4064)
			(end 0.7874 -0.4064)
			(stroke
				(width 0.1524)
				(type default)
			)
			(layer "B.SilkS")
		)
		(fp_line
			(start 0.7874 -0.4064)
			(end -0.7874 -0.4064)
			(stroke
				(width 0.1524)
				(type default)
			)
			(layer "B.SilkS")
		)
		(fp_line
			(start -0.7874 0.4064)
			(end 0.7874 0.4064)
			(stroke
				(width 0.1524)
				(type default)
			)
			(layer "B.SilkS")
		)
		(fp_line
			(start -0.7874 -0.4064)
			(end -0.7874 0.4064)
			(stroke
				(width 0.1524)
				(type default)
			)
			(layer "B.SilkS")
		)
		(fp_line
			(start 0.67945 0.3048)
			(end 0.67945 -0.305054)
			(stroke
				(width 0.1)
				(type default)
			)
			(layer "B.Fab")
		)
		(fp_line
			(start 0.67945 -0.305054)
			(end 0.12065 -0.305054)
			(stroke
				(width 0.1)
				(type default)
			)
			(layer "B.Fab")
		)
		(fp_line
			(start 0.12065 0.3048)
			(end 0.67945 0.3048)
			(stroke
				(width 0.1)
				(type default)
			)
			(layer "B.Fab")
		)
		(fp_line
			(start 0.12065 0.2794)
			(end 0.12065 0.3048)
			(stroke
				(width 0.1)
				(type default)
			)
			(layer "B.Fab")
		)
		(fp_line
			(start 0.12065 -0.2794)
			(end -0.12065 -0.2794)
			(stroke
				(width 0.1)
				(type default)
			)
			(layer "B.Fab")
		)
		(fp_line
			(start 0.12065 -0.305054)
			(end 0.12065 -0.2794)
			(stroke
				(width 0.1)
				(type default)
			)
			(layer "B.Fab")
		)
		(fp_line
			(start -0.120396 0.3048)
			(end -0.120396 0.2794)
			(stroke
				(width 0.1)
				(type default)
			)
			(layer "B.Fab")
		)
		(fp_line
			(start -0.120396 0.2794)
			(end 0.12065 0.2794)
			(stroke
				(width 0.1)
				(type default)
			)
			(layer "B.Fab")
		)
		(fp_line
			(start -0.12065 -0.2794)
			(end -0.12065 -0.3048)
			(stroke
				(width 0.1)
				(type default)
			)
			(layer "B.Fab")
		)
		(fp_line
			(start -0.12065 -0.3048)
			(end -0.67945 -0.3048)
			(stroke
				(width 0.1)
				(type default)
			)
			(layer "B.Fab")
		)
		(fp_line
			(start -0.67945 0.3048)
			(end -0.120396 0.3048)
			(stroke
				(width 0.1)
				(type default)
			)
			(layer "B.Fab")
		)
		(fp_line
			(start -0.67945 -0.3048)
			(end -0.67945 0.3048)
			(stroke
				(width 0.1)
				(type default)
			)
			(layer "B.Fab")
		)
		(pad "1" smd circle
			(at 0.40005 0)
			(size 0 0)
			(layers "B.Cu" "B.Mask" "B.Paste")
			(net "PVDDCR_SOC_P0")
		)
		(pad "2" smd circle
			(at -0.40005 0)
			(size 0 0)
			(layers "B.Cu" "B.Mask" "B.Paste")
			(net "GND")
		)
	)
	(footprint ""
		(layer "B.Cu")
		(at 217.17 -330.708 180)
		(property "Reference" "R6772"
			(at 0 0 0)
			(layer "B.SilkS")
			(hide yes)
			(effects
				(font
					(size 1.27 1.27)
				)
				(justify mirror)
			)
		)
		(property "Value" ""
			(at 0 0 0)
			(layer "B.Fab")
			(effects
				(font
					(size 1.27 1.27)
				)
				(justify mirror)
			)
		)
		(duplicate_pad_numbers_are_jumpers no)
		(fp_line
			(start 0.32512 0.175006)
			(end 0.32512 -0.175006)
			(stroke
				(width 0.1)
				(type default)
			)
			(layer "B.Fab")
		)
		(fp_line
			(start 0.32512 -0.175006)
			(end -0.32512 -0.175006)
			(stroke
				(width 0.1)
				(type default)
			)
			(layer "B.Fab")
		)
		(fp_line
			(start -0.32512 0.175006)
			(end 0.32512 0.175006)
			(stroke
				(width 0.1)
				(type default)
			)
			(layer "B.Fab")
		)
		(fp_line
			(start -0.32512 -0.175006)
			(end -0.32512 0.175006)
			(stroke
				(width 0.1)
				(type default)
			)
			(layer "B.Fab")
		)
		(pad "1" smd rect
			(at 0.2667 0)
			(size 0.3048 0.381)
			(layers "B.Cu" "B.Mask" "B.Paste")
			(net "P1V8_AUX")
		)
		(pad "2" smd rect
			(at -0.2667 0 180)
			(size 0.3048 0.381)
			(layers "B.Cu" "B.Mask" "B.Paste")
			(net "RT_SMB_MUX_ADDR0")
		)
	)
	(footprint ""
		(layer "B.Cu")
		(at 346.518992 -259.729986 180)
		(property "Reference" "C2655"
			(at 0 0 0)
			(layer "B.SilkS")
			(hide yes)
			(effects
				(font
					(size 1.27 1.27)
				)
				(justify mirror)
			)
		)
		(property "Value" ""
			(at 0 0 0)
			(layer "B.Fab")
			(effects
				(font
					(size 1.27 1.27)
				)
				(justify mirror)
			)
		)
		(duplicate_pad_numbers_are_jumpers no)
		(fp_line
			(start 0.7874 0.4064)
			(end 0.7874 -0.4064)
			(stroke
				(width 0.1524)
				(type default)
			)
			(layer "B.SilkS")
		)
		(fp_line
			(start 0.7874 -0.4064)
			(end -0.7874 -0.4064)
			(stroke
				(width 0.1524)
				(type default)
			)
			(layer "B.SilkS")
		)
		(fp_line
			(start -0.7874 0.4064)
			(end 0.7874 0.4064)
			(stroke
				(width 0.1524)
				(type default)
			)
			(layer "B.SilkS")
		)
		(fp_line
			(start -0.7874 -0.4064)
			(end -0.7874 0.4064)
			(stroke
				(width 0.1524)
				(type default)
			)
			(layer "B.SilkS")
		)
		(fp_line
			(start 0.67945 0.3048)
			(end 0.67945 -0.305054)
			(stroke
				(width 0.1)
				(type default)
			)
			(layer "B.Fab")
		)
		(fp_line
			(start 0.67945 -0.305054)
			(end 0.12065 -0.305054)
			(stroke
				(width 0.1)
				(type default)
			)
			(layer "B.Fab")
		)
		(fp_line
			(start 0.12065 0.3048)
			(end 0.67945 0.3048)
			(stroke
				(width 0.1)
				(type default)
			)
			(layer "B.Fab")
		)
		(fp_line
			(start 0.12065 0.2794)
			(end 0.12065 0.3048)
			(stroke
				(width 0.1)
				(type default)
			)
			(layer "B.Fab")
		)
		(fp_line
			(start 0.12065 -0.2794)
			(end -0.12065 -0.2794)
			(stroke
				(width 0.1)
				(type default)
			)
			(layer "B.Fab")
		)
		(fp_line
			(start 0.12065 -0.305054)
			(end 0.12065 -0.2794)
			(stroke
				(width 0.1)
				(type default)
			)
			(layer "B.Fab")
		)
		(fp_line
			(start -0.120396 0.3048)
			(end -0.120396 0.2794)
			(stroke
				(width 0.1)
				(type default)
			)
			(layer "B.Fab")
		)
		(fp_line
			(start -0.120396 0.2794)
			(end 0.12065 0.2794)
			(stroke
				(width 0.1)
				(type default)
			)
			(layer "B.Fab")
		)
		(fp_line
			(start -0.12065 -0.2794)
			(end -0.12065 -0.3048)
			(stroke
				(width 0.1)
				(type default)
			)
			(layer "B.Fab")
		)
		(fp_line
			(start -0.12065 -0.3048)
			(end -0.67945 -0.3048)
			(stroke
				(width 0.1)
				(type default)
			)
			(layer "B.Fab")
		)
		(fp_line
			(start -0.67945 0.3048)
			(end -0.120396 0.3048)
			(stroke
				(width 0.1)
				(type default)
			)
			(layer "B.Fab")
		)
		(fp_line
			(start -0.67945 -0.3048)
			(end -0.67945 0.3048)
			(stroke
				(width 0.1)
				(type default)
			)
			(layer "B.Fab")
		)
		(pad "1" smd circle
			(at 0.40005 0)
			(size 0 0)
			(layers "B.Cu" "B.Mask" "B.Paste")
			(net "PVDDIO_P0")
		)
		(pad "2" smd circle
			(at -0.40005 0)
			(size 0 0)
			(layers "B.Cu" "B.Mask" "B.Paste")
			(net "GND")
		)
	)
)
